(kicad_pcb
	(version 20260206)
	(generator "pcbnew")
	(generator_version "10.0")
	(general
		(thickness 1.6)
		(legacy_teardrops no)
	)
	(paper "A4")
	(title_block
		(title "03242023_DA0F0TMBIJ0_F0T_Motherboard_J_brd_V01_OCP.brd")
		(comment 1 "Grand Teton / footprint 3039 of 6105 (U2), pads 4325-4435 of 4677")
	)
	(layers
		(0 "F.Cu" signal "TOP")
		(4 "In1.Cu" signal "GND")
		(6 "In2.Cu" signal "IN1")
		(8 "In3.Cu" signal "GND1")
		(10 "In4.Cu" signal "IN2")
		(12 "In5.Cu" signal "GND2")
		(14 "In6.Cu" signal "IN3")
		(16 "In7.Cu" signal "GND3")
		(18 "In8.Cu" signal "VCC")
		(20 "In9.Cu" signal "VCC1")
		(22 "In10.Cu" signal "GND4")
		(24 "In11.Cu" signal "IN4")
		(26 "In12.Cu" signal "GND5")
		(28 "In13.Cu" signal "IN5")
		(30 "In14.Cu" signal "GND6")
		(32 "In15.Cu" signal "IN6")
		(34 "In16.Cu" signal "GND7")
		(2 "B.Cu" signal "BOTTOM")
		(9 "F.Adhes" user "F.Adhesive")
		(11 "B.Adhes" user "B.Adhesive")
		(13 "F.Paste" user "Package Geometry/Pastemask Top")
		(15 "B.Paste" user "Package Geometry/Pastemask Bottom")
		(5 "F.SilkS" user "Ref Des/Silkscreen Top")
		(7 "B.SilkS" user "Ref Des/Silkscreen Bottom")
		(1 "F.Mask" user "Board Geometry/Soldermask Top")
		(3 "B.Mask" user "Board Geometry/Soldermask Bottom")
		(17 "Dwgs.User" user "User.Drawings")
		(19 "Cmts.User" user "User.Comments")
		(21 "Eco1.User" user "User.Eco1")
		(23 "Eco2.User" user "User.Eco2")
		(25 "Edge.Cuts" user "Board Geometry/Outline")
		(27 "Margin" user)
		(31 "F.CrtYd" user "Package Geometry/Place Bound Top")
		(29 "B.CrtYd" user "Package Geometry/Place Bound Bottom")
		(35 "F.Fab" user "Ref Des/Assembly Top")
		(33 "B.Fab" user "Ref Des/Assembly Bottom")
	)
	(footprint ""
		(layer "F.Cu")
		(at 359.870248 -251.76988 90)
		(property "Reference" "U2"
			(at -74.416158 -44.488608 0)
			(unlocked yes)
			(layer "F.SilkS")
			(effects
				(font
					(size 1.6002 1.1938)
					(thickness 0.1524)
				)
				(justify left)
			)
		)
		(property "Value" ""
			(at 0 0 90)
			(layer "F.Fab")
			(effects
				(font
					(size 1.27 1.27)
				)
			)
		)
		(duplicate_pad_numbers_are_jumpers no)
		(pad "N15" smd circle
			(at -26.030682 -21.435314 270)
			(size 0.4318 0.4318)
			(layers "F.Cu" "F.Mask" "F.Paste")
			(net "GND")
		)
		(pad "N17" smd circle
			(at -24.402796 -21.435314 270)
			(size 0.4318 0.4318)
			(layers "F.Cu" "F.Mask" "F.Paste")
			(net "M_B_CPU0_SB_DQ<22>")
		)
		(pad "N19" smd circle
			(at -22.77491 -21.435314 270)
			(size 0.4318 0.4318)
			(layers "F.Cu" "F.Mask" "F.Paste")
			(net "M_B_CPU0_SB_DQ<19>")
		)
		(pad "N21" smd circle
			(at -21.147278 -21.435314 270)
			(size 0.4318 0.4318)
			(layers "F.Cu" "F.Mask" "F.Paste")
			(net "GND")
		)
		(pad "N23" smd circle
			(at -19.519392 -21.435314 270)
			(size 0.4318 0.4318)
			(layers "F.Cu" "F.Mask" "F.Paste")
			(net "M_B_CPU0_SB_DQ<14>")
		)
		(pad "N25" smd circle
			(at -17.89176 -21.435314 270)
			(size 0.4318 0.4318)
			(layers "F.Cu" "F.Mask" "F.Paste")
			(net "M_B_CPU0_SB_DQ<11>")
		)
		(pad "N27" smd circle
			(at -16.263874 -21.435314 270)
			(size 0.4318 0.4318)
			(layers "F.Cu" "F.Mask" "F.Paste")
			(net "GND")
		)
		(pad "N29" smd circle
			(at -14.635988 -21.435314 270)
			(size 0.4318 0.4318)
			(layers "F.Cu" "F.Mask" "F.Paste")
			(net "M_A_CPU0_SB_DQ<6>")
		)
		(pad "N31" smd circle
			(at -13.008356 -21.435314 270)
			(size 0.4318 0.4318)
			(layers "F.Cu" "F.Mask" "F.Paste")
			(net "M_A_CPU0_SB_DQ<3>")
		)
		(pad "N33" smd circle
			(at -11.380724 -21.435314 270)
			(size 0.4318 0.4318)
			(layers "F.Cu" "F.Mask" "F.Paste")
			(net "GND")
		)
		(pad "N35" smd circle
			(at -9.752838 -21.435314 270)
			(size 0.4318 0.4318)
			(layers "F.Cu" "F.Mask" "F.Paste")
			(net "M_B_CPU0_SB_CB<2>")
		)
		(pad "N37" smd circle
			(at -8.124952 -21.435314 270)
			(size 0.4318 0.4318)
			(layers "F.Cu" "F.Mask" "F.Paste")
			(net "M_B_CPU0_SB_CB<7>")
		)
		(pad "N39" smd circle
			(at -6.49732 -21.435314 270)
			(size 0.4318 0.4318)
			(layers "F.Cu" "F.Mask" "F.Paste")
			(net "GND")
		)
		(pad "N41" smd circle
			(at -4.869434 -21.435314 270)
			(size 0.4318 0.4318)
			(layers "F.Cu" "F.Mask" "F.Paste")
			(net "M_B_CPU0_SB_CS_N<2>")
		)
		(pad "N43" smd circle
			(at -3.241802 -21.435314 270)
			(size 0.4318 0.4318)
			(layers "F.Cu" "F.Mask" "F.Paste")
			(net "M_B_CPU0_SB_CA<5>")
		)
		(pad "N45" smd circle
			(at -1.613916 -21.435314 270)
			(size 0.4318 0.4318)
			(layers "F.Cu" "F.Mask" "F.Paste")
			(net "GND")
		)
		(pad "N48" smd circle
			(at 2.427732 -21.325332 270)
			(size 0.4318 0.4318)
			(layers "F.Cu" "F.Mask" "F.Paste")
			(net "M_B_CPU0_SA_CA<3>")
		)
		(pad "N50" smd circle
			(at 4.055618 -21.325332 270)
			(size 0.4318 0.4318)
			(layers "F.Cu" "F.Mask" "F.Paste")
			(net "M_B_CPU0_SA_CS_N<3>")
		)
		(pad "N52" smd circle
			(at 5.68325 -21.325332 270)
			(size 0.4318 0.4318)
			(layers "F.Cu" "F.Mask" "F.Paste")
			(net "GND")
		)
		(pad "N54" smd circle
			(at 7.311136 -21.325332 270)
			(size 0.4318 0.4318)
			(layers "F.Cu" "F.Mask" "F.Paste")
			(net "M_B_CPU0_SA_CB<6>")
		)
		(pad "N56" smd circle
			(at 8.939022 -21.325332 270)
			(size 0.4318 0.4318)
			(layers "F.Cu" "F.Mask" "F.Paste")
			(net "M_B_CPU0_SA_CB<3>")
		)
		(pad "N58" smd circle
			(at 10.566654 -21.325332 270)
			(size 0.4318 0.4318)
			(layers "F.Cu" "F.Mask" "F.Paste")
			(net "GND")
		)
		(pad "N60" smd circle
			(at 12.19454 -21.325332 270)
			(size 0.4318 0.4318)
			(layers "F.Cu" "F.Mask" "F.Paste")
			(net "M_B_CPU0_SA_DQ<22>")
		)
		(pad "N62" smd circle
			(at 13.822426 -21.325332 270)
			(size 0.4318 0.4318)
			(layers "F.Cu" "F.Mask" "F.Paste")
			(net "M_B_CPU0_SA_DQ<19>")
		)
		(pad "N64" smd circle
			(at 15.450058 -21.325332 270)
			(size 0.4318 0.4318)
			(layers "F.Cu" "F.Mask" "F.Paste")
			(net "GND")
		)
		(pad "N66" smd circle
			(at 17.07769 -21.325332 270)
			(size 0.4318 0.4318)
			(layers "F.Cu" "F.Mask" "F.Paste")
			(net "M_A_CPU0_SA_DQ<14>")
		)
		(pad "N68" smd circle
			(at 18.705576 -21.325332 270)
			(size 0.4318 0.4318)
			(layers "F.Cu" "F.Mask" "F.Paste")
			(net "M_A_CPU0_SA_DQ<11>")
		)
		(pad "N70" smd circle
			(at 20.333462 -21.325332 270)
			(size 0.4318 0.4318)
			(layers "F.Cu" "F.Mask" "F.Paste")
			(net "GND")
		)
		(pad "N72" smd circle
			(at 21.961094 -21.325332 270)
			(size 0.4318 0.4318)
			(layers "F.Cu" "F.Mask" "F.Paste")
			(net "M_B_CPU0_SA_DQ<6>")
		)
		(pad "N74" smd circle
			(at 23.58898 -21.325332 270)
			(size 0.4318 0.4318)
			(layers "F.Cu" "F.Mask" "F.Paste")
			(net "M_B_CPU0_SA_DQ<3>")
		)
		(pad "N76" smd circle
			(at 25.216612 -21.325332 270)
			(size 0.4318 0.4318)
			(layers "F.Cu" "F.Mask" "F.Paste")
			(net "GND")
		)
		(pad "N78" smd circle
			(at 26.844498 -21.325332 270)
			(size 0.4318 0.4318)
			(layers "F.Cu" "F.Mask" "F.Paste")
			(net "GND")
		)
		(pad "N80" smd circle
			(at 28.472384 -21.325332 270)
			(size 0.4318 0.4318)
			(layers "F.Cu" "F.Mask" "F.Paste")
			(net "GND")
		)
		(pad "N82" smd circle
			(at 30.100016 -21.325332 270)
			(size 0.4318 0.4318)
			(layers "F.Cu" "F.Mask" "F.Paste")
			(net "GND")
		)
		(pad "N84" smd circle
			(at 31.727902 -21.325332 270)
			(size 0.4318 0.4318)
			(layers "F.Cu" "F.Mask" "F.Paste")
			(net "GND")
		)
		(pad "N86" smd circle
			(at 33.355534 -21.325332 270)
			(size 0.4318 0.4318)
			(layers "F.Cu" "F.Mask" "F.Paste")
			(net "P5E_CPU0_PE4_TX_DP<1>")
		)
		(pad "N88" smd circle
			(at 34.98342 -21.325332 270)
			(size 0.4318 0.4318)
			(layers "F.Cu" "F.Mask" "F.Paste")
			(net "GND")
		)
		(pad "N90" smd oval
			(at 36.611306 -21.325332)
			(size 0.381 0.4826)
			(drill
				(offset 0 -0.0508)
			)
			(layers "F.Cu" "F.Mask" "F.Paste")
			(net "P5E_CPU0_PE4_RX_DP<1>")
		)
		(pad "P2" smd circle
			(at -36.611306 -20.965668 270)
			(size 0.4318 0.4318)
			(layers "F.Cu" "F.Mask" "F.Paste")
			(net "UPI_CPU0_CPU1_P0P1_DP<2>")
		)
		(pad "P4" smd circle
			(at -34.98342 -20.965668 270)
			(size 0.4318 0.4318)
			(layers "F.Cu" "F.Mask" "F.Paste")
			(net "GND")
		)
		(pad "P6" smd circle
			(at -33.355534 -20.965668 270)
			(size 0.4318 0.4318)
			(layers "F.Cu" "F.Mask" "F.Paste")
			(net "UPI_CPU1_CPU0_P1P0_DN<2>")
		)
		(pad "P8" smd circle
			(at -31.727902 -20.965668 270)
			(size 0.4318 0.4318)
			(layers "F.Cu" "F.Mask" "F.Paste")
			(net "GND")
		)
		(pad "P10" smd circle
			(at -30.100016 -20.965668 270)
			(size 0.4318 0.4318)
			(layers "F.Cu" "F.Mask" "F.Paste")
			(net "P5E_CPU0_PE0_RX_DN<2>")
		)
		(pad "P12" smd circle
			(at -28.472384 -20.965668 270)
			(size 0.4318 0.4318)
			(layers "F.Cu" "F.Mask" "F.Paste")
			(net "GND")
		)
		(pad "P14" smd circle
			(at -26.844498 -20.965668 270)
			(size 0.4318 0.4318)
			(layers "F.Cu" "F.Mask" "F.Paste")
			(net "P5E_CPU0_PE0_TX_DN<1>")
		)
		(pad "P16" smd circle
			(at -25.216612 -20.965668 270)
			(size 0.4318 0.4318)
			(layers "F.Cu" "F.Mask" "F.Paste")
			(net "GND")
		)
		(pad "P18" smd circle
			(at -23.58898 -20.965668 270)
			(size 0.4318 0.4318)
			(layers "F.Cu" "F.Mask" "F.Paste")
			(net "M_B_CPU0_SB_DQS_DP<7>")
		)
		(pad "P20" smd circle
			(at -21.961094 -20.965668 270)
			(size 0.4318 0.4318)
			(layers "F.Cu" "F.Mask" "F.Paste")
			(net "GND")
		)
		(pad "P22" smd circle
			(at -20.333462 -20.965668 270)
			(size 0.4318 0.4318)
			(layers "F.Cu" "F.Mask" "F.Paste")
			(net "GND")
		)
		(pad "P24" smd circle
			(at -18.705576 -20.965668 270)
			(size 0.4318 0.4318)
			(layers "F.Cu" "F.Mask" "F.Paste")
			(net "M_B_CPU0_SB_DQS_DP<6>")
		)
		(pad "P26" smd circle
			(at -17.07769 -20.965668 270)
			(size 0.4318 0.4318)
			(layers "F.Cu" "F.Mask" "F.Paste")
			(net "GND")
		)
		(pad "P28" smd circle
			(at -15.450058 -20.965668 270)
			(size 0.4318 0.4318)
			(layers "F.Cu" "F.Mask" "F.Paste")
			(net "GND")
		)
		(pad "P30" smd circle
			(at -13.822426 -20.965668 270)
			(size 0.4318 0.4318)
			(layers "F.Cu" "F.Mask" "F.Paste")
			(net "M_A_CPU0_SB_DQS_DP<5>")
		)
		(pad "P32" smd circle
			(at -12.19454 -20.965668 270)
			(size 0.4318 0.4318)
			(layers "F.Cu" "F.Mask" "F.Paste")
			(net "GND")
		)
		(pad "P34" smd circle
			(at -10.566654 -20.965668 270)
			(size 0.4318 0.4318)
			(layers "F.Cu" "F.Mask" "F.Paste")
			(net "GND")
		)
		(pad "P36" smd circle
			(at -8.939022 -20.965668 270)
			(size 0.4318 0.4318)
			(layers "F.Cu" "F.Mask" "F.Paste")
			(net "M_B_CPU0_SB_DQS_DN<4>")
		)
		(pad "P38" smd circle
			(at -7.311136 -20.965668 270)
			(size 0.4318 0.4318)
			(layers "F.Cu" "F.Mask" "F.Paste")
			(net "GND")
		)
		(pad "P40" smd circle
			(at -5.68325 -20.965668 270)
			(size 0.4318 0.4318)
			(layers "F.Cu" "F.Mask" "F.Paste")
			(net "GND")
		)
		(pad "P42" smd circle
			(at -4.055618 -20.965668 270)
			(size 0.4318 0.4318)
			(layers "F.Cu" "F.Mask" "F.Paste")
			(net "M_B_CPU0_SB_PAR")
		)
		(pad "P44" smd circle
			(at -2.427732 -20.965668 270)
			(size 0.4318 0.4318)
			(layers "F.Cu" "F.Mask" "F.Paste")
			(net "GND")
		)
		(pad "P47" smd circle
			(at 1.613916 -20.855686 270)
			(size 0.4318 0.4318)
			(layers "F.Cu" "F.Mask" "F.Paste")
			(net "GND")
		)
		(pad "P49" smd circle
			(at 3.241802 -20.855686 270)
			(size 0.4318 0.4318)
			(layers "F.Cu" "F.Mask" "F.Paste")
			(net "M_B_CPU0_SA_CA<1>")
		)
		(pad "P51" smd circle
			(at 4.869434 -20.855686 270)
			(size 0.4318 0.4318)
			(layers "F.Cu" "F.Mask" "F.Paste")
			(net "GND")
		)
		(pad "P53" smd circle
			(at 6.49732 -20.855686 270)
			(size 0.4318 0.4318)
			(layers "F.Cu" "F.Mask" "F.Paste")
			(net "GND")
		)
		(pad "P55" smd circle
			(at 8.124952 -20.855686 270)
			(size 0.4318 0.4318)
			(layers "F.Cu" "F.Mask" "F.Paste")
			(net "M_B_CPU0_SA_DQS_DP<9>")
		)
		(pad "P57" smd circle
			(at 9.752838 -20.855686 270)
			(size 0.4318 0.4318)
			(layers "F.Cu" "F.Mask" "F.Paste")
			(net "GND")
		)
		(pad "P59" smd circle
			(at 11.380724 -20.855686 270)
			(size 0.4318 0.4318)
			(layers "F.Cu" "F.Mask" "F.Paste")
			(net "GND")
		)
		(pad "P61" smd circle
			(at 13.008356 -20.855686 270)
			(size 0.4318 0.4318)
			(layers "F.Cu" "F.Mask" "F.Paste")
			(net "M_B_CPU0_SA_DQS_DP<7>")
		)
		(pad "P63" smd circle
			(at 14.635988 -20.855686 270)
			(size 0.4318 0.4318)
			(layers "F.Cu" "F.Mask" "F.Paste")
			(net "GND")
		)
		(pad "P65" smd circle
			(at 16.263874 -20.855686 270)
			(size 0.4318 0.4318)
			(layers "F.Cu" "F.Mask" "F.Paste")
			(net "GND")
		)
		(pad "P67" smd circle
			(at 17.89176 -20.855686 270)
			(size 0.4318 0.4318)
			(layers "F.Cu" "F.Mask" "F.Paste")
			(net "M_A_CPU0_SA_DQS_DN<6>")
		)
		(pad "P69" smd circle
			(at 19.519392 -20.855686 270)
			(size 0.4318 0.4318)
			(layers "F.Cu" "F.Mask" "F.Paste")
			(net "GND")
		)
		(pad "P71" smd circle
			(at 21.147278 -20.855686 270)
			(size 0.4318 0.4318)
			(layers "F.Cu" "F.Mask" "F.Paste")
			(net "GND")
		)
		(pad "P73" smd circle
			(at 22.77491 -20.855686 270)
			(size 0.4318 0.4318)
			(layers "F.Cu" "F.Mask" "F.Paste")
			(net "M_B_CPU0_SA_DQS_DP<5>")
		)
		(pad "P75" smd circle
			(at 24.402796 -20.855686 270)
			(size 0.4318 0.4318)
			(layers "F.Cu" "F.Mask" "F.Paste")
			(net "GND")
		)
		(pad "P77" smd circle
			(at 26.030682 -20.855686 270)
			(size 0.4318 0.4318)
			(layers "F.Cu" "F.Mask" "F.Paste")
			(net "GND")
		)
		(pad "P79" smd circle
			(at 27.658314 -20.855686 270)
			(size 0.4318 0.4318)
			(layers "F.Cu" "F.Mask" "F.Paste")
			(net "PVCCFA_EHV_FIVRA_CPU0")
		)
		(pad "P81" smd circle
			(at 29.2862 -20.855686 270)
			(size 0.4318 0.4318)
			(layers "F.Cu" "F.Mask" "F.Paste")
			(net "UPI_CPU0_CPU1_P2P2_DN<18>")
		)
		(pad "P83" smd circle
			(at 30.914086 -20.855686 270)
			(size 0.4318 0.4318)
			(layers "F.Cu" "F.Mask" "F.Paste")
			(net "UPI_CPU0_CPU1_P2P2_DP<17>")
		)
		(pad "P85" smd circle
			(at 32.541718 -20.855686 270)
			(size 0.4318 0.4318)
			(layers "F.Cu" "F.Mask" "F.Paste")
			(net "P5E_CPU0_PE4_TX_DN<1>")
		)
		(pad "P87" smd circle
			(at 34.169604 -20.855686 270)
			(size 0.4318 0.4318)
			(layers "F.Cu" "F.Mask" "F.Paste")
			(net "GND")
		)
		(pad "P89" smd circle
			(at 35.797236 -20.855686 270)
			(size 0.4318 0.4318)
			(layers "F.Cu" "F.Mask" "F.Paste")
			(net "P5E_CPU0_PE4_RX_DN<1>")
		)
		(pad "P91" smd oval
			(at 37.425122 -20.855686)
			(size 0.381 0.4826)
			(drill
				(offset 0 -0.0508)
			)
			(layers "F.Cu" "F.Mask" "F.Paste")
			(net "GND")
		)
		(pad "R1" smd oval
			(at -37.425122 -20.495514 180)
			(size 0.381 0.4826)
			(drill
				(offset 0 -0.0508)
			)
			(layers "F.Cu" "F.Mask" "F.Paste")
			(net "GND")
		)
		(pad "R3" smd circle
			(at -35.797236 -20.495514 270)
			(size 0.4318 0.4318)
			(layers "F.Cu" "F.Mask" "F.Paste")
			(net "UPI_CPU0_CPU1_P0P1_DP<3>")
		)
		(pad "R5" smd circle
			(at -34.169604 -20.495514 270)
			(size 0.4318 0.4318)
			(layers "F.Cu" "F.Mask" "F.Paste")
			(net "GND")
		)
		(pad "R7" smd circle
			(at -32.541718 -20.495514 270)
			(size 0.4318 0.4318)
			(layers "F.Cu" "F.Mask" "F.Paste")
			(net "UPI_CPU1_CPU0_P1P0_DP<2>")
		)
		(pad "R9" smd circle
			(at -30.914086 -20.495514 270)
			(size 0.4318 0.4318)
			(layers "F.Cu" "F.Mask" "F.Paste")
			(net "GND")
		)
		(pad "R11" smd circle
			(at -29.2862 -20.495514 270)
			(size 0.4318 0.4318)
			(layers "F.Cu" "F.Mask" "F.Paste")
			(net "P5E_CPU0_PE0_RX_DP<2>")
		)
		(pad "R13" smd circle
			(at -27.658314 -20.495514 270)
			(size 0.4318 0.4318)
			(layers "F.Cu" "F.Mask" "F.Paste")
			(net "GND")
		)
		(pad "R15" smd circle
			(at -26.030682 -20.495514 270)
			(size 0.4318 0.4318)
			(layers "F.Cu" "F.Mask" "F.Paste")
			(net "P5E_CPU0_PE0_TX_DP<1>")
		)
		(pad "R17" smd circle
			(at -24.402796 -20.495514 270)
			(size 0.4318 0.4318)
			(layers "F.Cu" "F.Mask" "F.Paste")
			(net "GND")
		)
		(pad "R19" smd circle
			(at -22.77491 -20.495514 270)
			(size 0.4318 0.4318)
			(layers "F.Cu" "F.Mask" "F.Paste")
			(net "GND")
		)
		(pad "R21" smd circle
			(at -21.147278 -20.495514 270)
			(size 0.4318 0.4318)
			(layers "F.Cu" "F.Mask" "F.Paste")
			(net "M_C_CPU0_SB_DQS_DN<2>")
		)
		(pad "R23" smd circle
			(at -19.519392 -20.495514 270)
			(size 0.4318 0.4318)
			(layers "F.Cu" "F.Mask" "F.Paste")
			(net "GND")
		)
		(pad "R25" smd circle
			(at -17.89176 -20.495514 270)
			(size 0.4318 0.4318)
			(layers "F.Cu" "F.Mask" "F.Paste")
			(net "GND")
		)
		(pad "R27" smd circle
			(at -16.263874 -20.495514 270)
			(size 0.4318 0.4318)
			(layers "F.Cu" "F.Mask" "F.Paste")
			(net "M_B_CPU0_SB_DQS_DN<0>")
		)
		(pad "R29" smd circle
			(at -14.635988 -20.495514 270)
			(size 0.4318 0.4318)
			(layers "F.Cu" "F.Mask" "F.Paste")
			(net "GND")
		)
		(pad "R31" smd circle
			(at -13.008356 -20.495514 270)
			(size 0.4318 0.4318)
			(layers "F.Cu" "F.Mask" "F.Paste")
			(net "GND")
		)
		(pad "R33" smd circle
			(at -11.380724 -20.495514 270)
			(size 0.4318 0.4318)
			(layers "F.Cu" "F.Mask" "F.Paste")
			(net "M_C_CPU0_SB_DQS_DN<9>")
		)
		(pad "R35" smd circle
			(at -9.752838 -20.495514 270)
			(size 0.4318 0.4318)
			(layers "F.Cu" "F.Mask" "F.Paste")
			(net "GND")
		)
		(pad "R37" smd circle
			(at -8.124952 -20.495514 270)
			(size 0.4318 0.4318)
			(layers "F.Cu" "F.Mask" "F.Paste")
			(net "GND")
		)
		(pad "R39" smd circle
			(at -6.49732 -20.495514 270)
			(size 0.4318 0.4318)
			(layers "F.Cu" "F.Mask" "F.Paste")
			(net "M_C_CPU0_SB_CA<6>")
		)
		(pad "R41" smd circle
			(at -4.869434 -20.495514 270)
			(size 0.4318 0.4318)
			(layers "F.Cu" "F.Mask" "F.Paste")
			(net "GND")
		)
		(pad "R43" smd circle
			(at -3.241802 -20.495514 270)
			(size 0.4318 0.4318)
			(layers "F.Cu" "F.Mask" "F.Paste")
			(net "GND")
		)
		(pad "R45" smd circle
			(at -1.613916 -20.495514 270)
			(size 0.4318 0.4318)
			(layers "F.Cu" "F.Mask" "F.Paste")
			(net "M_B_CPU0_CLK_DN<0>")
		)
		(pad "R48" smd circle
			(at 2.427732 -20.385532 270)
			(size 0.4318 0.4318)
			(layers "F.Cu" "F.Mask" "F.Paste")
			(net "GND")
		)
		(pad "R50" smd circle
			(at 4.055618 -20.385532 270)
			(size 0.4318 0.4318)
			(layers "F.Cu" "F.Mask" "F.Paste")
			(net "GND")
		)
		(pad "R52" smd circle
			(at 5.68325 -20.385532 270)
			(size 0.4318 0.4318)
			(layers "F.Cu" "F.Mask" "F.Paste")
			(net "M_C_CPU0_SA_CA<0>")
		)
		(pad "R54" smd circle
			(at 7.311136 -20.385532 270)
			(size 0.4318 0.4318)
			(layers "F.Cu" "F.Mask" "F.Paste")
			(net "GND")
		)
		(pad "R56" smd circle
			(at 8.939022 -20.385532 270)
			(size 0.4318 0.4318)
			(layers "F.Cu" "F.Mask" "F.Paste")
			(net "GND")
		)
	)
)
